# CM4 Baseboard — KiCad custom design rules (.kicad_dru)
(version 1)

(rule "Inner CSI"
	(layer inner)
	(condition "A.NetClass == '100Ohm-diff_CSI' && A.inDiffPair('*')")
	(constraint diff_pair_gap (opt 0.335mm))
	(constraint track_width (opt 0.138mm))
)

(rule "Track-edge clearance"
	(condition "A.Type == 'Track'")
	(constraint edge_clearance (min 0.4mm))
)

